# T6G (Grand Teton) — schematic netlist excerpt (pin names and nets, part order shuffled) for the footprints in the layout excerpt that follows; sources: Cadence DE-HDL packaged netlist, KiCad conversion of 04192023_DAF0TMB3IC0_F0TG_MB_C_brd_V02_OCP.brd

PU295  MAX15090BEWIT  MAX15090BEWI+T IC  pkg BGA28_0-5_3-525X2-065  page 146
  ISENSE  = P3V3_E1S_SENSE_0
  VCC  = P3V3_E1S_VCC_0
  IN_A3  = P3V3_AUX
  OUT_A4  = P3V3_E1S_0_R
  IN_A5  = P3V3_AUX
  GATE  = P3V3_E1S_GATE_0
  CDLY  = GND
  CB  = P3V3_E1S_CB_0
  GND_B2  = GND
  IN_B3  = P3V3_AUX
  OUT_B4  = P3V3_E1S_0_R
  IN_B5  = P3V3_AUX
  OUT_B6  = P3V3_E1S_0_R
  \en#\  = GND
  GND_C1  = GND
  GND_C2  = GND
  IN_C3  = P3V3_AUX
  OUT_C4  = P3V3_E1S_0_R
  IN_C5  = P3V3_AUX
  OUT_C6  = P3V3_E1S_0_R
  \fault#\  = P3V3_E1S_FAULT_0
  REG  = P3V3_E1S_REG_0
  UV  = P3V3_E1S_UV_0
  OV  = P3V3_E1S_OV_0
  OUT_D4  = P3V3_E1S_0_R
  IN_D5  = P3V3_AUX
  OUT_D6  = P3V3_E1S_0_R
  PG  = P3V3_E1S_PWRGD_0

(kicad_pcb
	(version 20260206)
	(generator "pcbnew")
	(generator_version "10.0")
	(general
		(thickness 1.6)
		(legacy_teardrops no)
	)
	(paper "A4")
	(title_block
		(title "04192023_DAF0TMB3IC0_F0TG_MB_C_brd_V02_OCP.brd")
		(comment 1 "Grand Teton / footprints 1078-1078 of 8354")
	)
	(layers
		(0 "F.Cu" signal "TOP")
		(4 "In1.Cu" signal "GND")
		(6 "In2.Cu" signal "IN1")
		(8 "In3.Cu" signal "GND1")
		(10 "In4.Cu" signal "IN2")
		(12 "In5.Cu" signal "GND2")
		(14 "In6.Cu" signal "IN3")
		(16 "In7.Cu" signal "GND3")
		(18 "In8.Cu" signal "VCC")
		(20 "In9.Cu" signal "VCC1")
		(22 "In10.Cu" signal "GND4")
		(24 "In11.Cu" signal "IN4")
		(26 "In12.Cu" signal "GND5")
		(28 "In13.Cu" signal "IN5")
		(30 "In14.Cu" signal "GND6")
		(32 "In15.Cu" signal "IN6")
		(34 "In16.Cu" signal "GND7")
		(2 "B.Cu" signal "BOTTOM")
		(9 "F.Adhes" user "F.Adhesive")
		(11 "B.Adhes" user "B.Adhesive")
		(13 "F.Paste" user "Package Geometry/Pastemask Top")
		(15 "B.Paste" user "Package Geometry/Pastemask Bottom")
		(5 "F.SilkS" user "Ref Des/Silkscreen Top")
		(7 "B.SilkS" user "Ref Des/Silkscreen Bottom")
		(1 "F.Mask" user "Board Geometry/Soldermask Top")
		(3 "B.Mask" user "Board Geometry/Soldermask Bottom")
		(17 "Dwgs.User" user "User.Drawings")
		(19 "Cmts.User" user "User.Comments")
		(21 "Eco1.User" user "User.Eco1")
		(23 "Eco2.User" user "User.Eco2")
		(25 "Edge.Cuts" user "Board Geometry/Outline")
		(27 "Margin" user)
		(31 "F.CrtYd" user "Package Geometry/Place Bound Top")
		(29 "B.CrtYd" user "Package Geometry/Place Bound Bottom")
		(35 "F.Fab" user "Ref Des/Assembly Top")
		(33 "B.Fab" user "Ref Des/Assembly Bottom")
	)
	(footprint ""
		(layer "F.Cu")
		(at 221.821502 -70.870318)
		(property "Reference" "PU295"
			(at -1.640332 2.305558 0)
			(unlocked yes)
			(layer "F.SilkS")
			(effects
				(font
					(size 0.7874 0.5842)
					(thickness 0.1524)
				)
				(justify left)
			)
		)
		(property "Value" ""
			(at 0 0 0)
			(layer "F.Fab")
			(effects
				(font
					(size 1.27 1.27)
				)
			)
		)
		(duplicate_pad_numbers_are_jumpers no)
		(fp_line
			(start -1.774952 -1.039876)
			(end -1.774952 1.039876)
			(stroke
				(width 0.1524)
				(type default)
			)
			(layer "F.SilkS")
		)
		(fp_line
			(start -1.774952 1.039876)
			(end 1.774952 1.039876)
			(stroke
				(width 0.1524)
				(type default)
			)
			(layer "F.SilkS")
		)
		(fp_line
			(start 1.774952 -1.039876)
			(end -1.774952 -1.039876)
			(stroke
				(width 0.1524)
				(type default)
			)
			(layer "F.SilkS")
		)
		(fp_line
			(start 1.774952 1.039876)
			(end 1.774952 -1.039876)
			(stroke
				(width 0.1524)
				(type default)
			)
			(layer "F.SilkS")
		)
		(fp_poly
			(pts
				(xy -0.999998 -1.801876) (xy -0.999998 -1.039876) (xy -1.769872 -1.039876) (xy -1.769872 -0.249936)
				(xy -2.531872 -0.249936) (xy -2.531872 -1.801876)
			)
			(stroke
				(width 0)
				(type default)
			)
			(fill yes)
			(layer "F.SilkS")
		)
		(fp_line
			(start -1.769872 -1.039876)
			(end -1.769872 1.039876)
			(stroke
				(width 0.1)
				(type default)
			)
			(layer "F.Fab")
		)
		(fp_line
			(start -1.769872 1.039876)
			(end 1.769872 1.039876)
			(stroke
				(width 0.1)
				(type default)
			)
			(layer "F.Fab")
		)
		(fp_line
			(start 1.769872 -1.039876)
			(end -1.769872 -1.039876)
			(stroke
				(width 0.1)
				(type default)
			)
			(layer "F.Fab")
		)
		(fp_line
			(start 1.769872 1.039876)
			(end 1.769872 -1.039876)
			(stroke
				(width 0.1)
				(type default)
			)
			(layer "F.Fab")
		)
		(fp_poly
			(pts
				(xy -1.769872 -1.039876) (xy -0.999998 -1.039876) (xy -0.999998 -1.801876) (xy -2.531872 -1.801876)
				(xy -2.531872 -0.249936) (xy -1.769872 -0.249936)
			)
			(stroke
				(width 0)
				(type default)
			)
			(fill yes)
			(layer "F.Fab")
		)
		(pad "A1" smd circle
			(at -1.500124 -0.750062)
			(size 0.2286 0.2286)
			(layers "F.Cu" "F.Mask" "F.Paste")
			(net "P3V3_E1S_SENSE_0")
		)
		(pad "A2" smd circle
			(at -0.999998 -0.750062)
			(size 0.2286 0.2286)
			(layers "F.Cu" "F.Mask" "F.Paste")
			(net "P3V3_E1S_VCC_0")
		)
		(pad "A3" smd circle
			(at -0.499872 -0.750062)
			(size 0.2286 0.2286)
			(layers "F.Cu" "F.Mask" "F.Paste")
			(net "P3V3_AUX")
		)
		(pad "A4" smd circle
			(at 0 -0.750062)
			(size 0.2286 0.2286)
			(layers "F.Cu" "F.Mask" "F.Paste")
			(net "P3V3_E1S_0_R")
		)
		(pad "A5" smd circle
			(at 0.499872 -0.750062)
			(size 0.2286 0.2286)
			(layers "F.Cu" "F.Mask" "F.Paste")
			(net "P3V3_AUX")
		)
		(pad "A6" smd circle
			(at 0.999998 -0.750062)
			(size 0.2286 0.2286)
			(layers "F.Cu" "F.Mask" "F.Paste")
			(net "P3V3_E1S_GATE_0")
		)
		(pad "A7" smd circle
			(at 1.500124 -0.750062)
			(size 0.2286 0.2286)
			(layers "F.Cu" "F.Mask" "F.Paste")
			(net "GND")
		)
		(pad "B1" smd circle
			(at -1.500124 -0.249936)
			(size 0.2286 0.2286)
			(layers "F.Cu" "F.Mask" "F.Paste")
			(net "P3V3_E1S_CB_0")
		)
		(pad "B2" smd circle
			(at -0.999998 -0.249936)
			(size 0.2286 0.2286)
			(layers "F.Cu" "F.Mask" "F.Paste")
			(net "GND")
		)
		(pad "B3" smd circle
			(at -0.499872 -0.249936)
			(size 0.2286 0.2286)
			(layers "F.Cu" "F.Mask" "F.Paste")
			(net "P3V3_AUX")
		)
		(pad "B4" smd circle
			(at 0 -0.249936)
			(size 0.2286 0.2286)
			(layers "F.Cu" "F.Mask" "F.Paste")
			(net "P3V3_E1S_0_R")
		)
		(pad "B5" smd circle
			(at 0.499872 -0.249936)
			(size 0.2286 0.2286)
			(layers "F.Cu" "F.Mask" "F.Paste")
			(net "P3V3_AUX")
		)
		(pad "B6" smd circle
			(at 0.999998 -0.249936)
			(size 0.2286 0.2286)
			(layers "F.Cu" "F.Mask" "F.Paste")
			(net "P3V3_E1S_0_R")
		)
		(pad "B7" smd circle
			(at 1.500124 -0.249936)
			(size 0.2286 0.2286)
			(layers "F.Cu" "F.Mask" "F.Paste")
			(net "GND")
		)
		(pad "C1" smd circle
			(at -1.500124 0.249936)
			(size 0.2286 0.2286)
			(layers "F.Cu" "F.Mask" "F.Paste")
			(net "GND")
		)
		(pad "C2" smd circle
			(at -0.999998 0.249936)
			(size 0.2286 0.2286)
			(layers "F.Cu" "F.Mask" "F.Paste")
			(net "GND")
		)
		(pad "C3" smd circle
			(at -0.499872 0.249936)
			(size 0.2286 0.2286)
			(layers "F.Cu" "F.Mask" "F.Paste")
			(net "P3V3_AUX")
		)
		(pad "C4" smd circle
			(at 0 0.249936)
			(size 0.2286 0.2286)
			(layers "F.Cu" "F.Mask" "F.Paste")
			(net "P3V3_E1S_0_R")
		)
		(pad "C5" smd circle
			(at 0.499872 0.249936)
			(size 0.2286 0.2286)
			(layers "F.Cu" "F.Mask" "F.Paste")
			(net "P3V3_AUX")
		)
		(pad "C6" smd circle
			(at 0.999998 0.249936)
			(size 0.2286 0.2286)
			(layers "F.Cu" "F.Mask" "F.Paste")
			(net "P3V3_E1S_0_R")
		)
		(pad "C7" smd circle
			(at 1.500124 0.249936)
			(size 0.2286 0.2286)
			(layers "F.Cu" "F.Mask" "F.Paste")
			(net "P3V3_E1S_FAULT_0")
		)
		(pad "D1" smd circle
			(at -1.500124 0.750062)
			(size 0.2286 0.2286)
			(layers "F.Cu" "F.Mask" "F.Paste")
			(net "P3V3_E1S_REG_0")
		)
		(pad "D2" smd circle
			(at -0.999998 0.750062)
			(size 0.2286 0.2286)
			(layers "F.Cu" "F.Mask" "F.Paste")
			(net "P3V3_E1S_UV_0")
		)
		(pad "D3" smd circle
			(at -0.499872 0.750062)
			(size 0.2286 0.2286)
			(layers "F.Cu" "F.Mask" "F.Paste")
			(net "P3V3_E1S_OV_0")
		)
		(pad "D4" smd circle
			(at 0 0.750062)
			(size 0.2286 0.2286)
			(layers "F.Cu" "F.Mask" "F.Paste")
			(net "P3V3_E1S_0_R")
		)
		(pad "D5" smd circle
			(at 0.499872 0.750062)
			(size 0.2286 0.2286)
			(layers "F.Cu" "F.Mask" "F.Paste")
			(net "P3V3_AUX")
		)
		(pad "D6" smd circle
			(at 0.999998 0.750062)
			(size 0.2286 0.2286)
			(layers "F.Cu" "F.Mask" "F.Paste")
			(net "P3V3_E1S_0_R")
		)
		(pad "D7" smd circle
			(at 1.500124 0.750062)
			(size 0.2286 0.2286)
			(layers "F.Cu" "F.Mask" "F.Paste")
			(net "P3V3_E1S_PWRGD_0")
		)
	)
)
